(kicad_pcb
	(version 20260206)
	(generator "pcbnew")
	(generator_version "10.0")
	(general
		(thickness 1.6)
		(legacy_teardrops no)
	)
	(paper "A4")
	(title_block
		(title "timecard-production-celestica-r4006 — R4006-B0001-02_R01.brd")
		(comment 1 "Time Appliance Project (Time Card) / footprints 1105-1109 of 1113")
	)
	(layers
		(0 "F.Cu" signal "TOP")
		(4 "In1.Cu" signal "L02_GND1")
		(6 "In2.Cu" signal "L03_SIG1")
		(8 "In3.Cu" signal "L04_GND2")
		(10 "In4.Cu" signal "L05_VCC1")
		(12 "In5.Cu" signal "L06_VCC2")
		(14 "In6.Cu" signal "L07_GND3")
		(16 "In7.Cu" signal "L08_SIG2")
		(18 "In8.Cu" signal "L09_GND4")
		(2 "B.Cu" signal "BOTTOM")
		(9 "F.Adhes" user "F.Adhesive")
		(11 "B.Adhes" user "B.Adhesive")
		(13 "F.Paste" user "Package Geometry/Pastemask Top")
		(15 "B.Paste" user "Package Geometry/Pastemask Bottom")
		(5 "F.SilkS" user "Ref Des/Silkscreen Top")
		(7 "B.SilkS" user "Ref Des/Silkscreen Bottom")
		(1 "F.Mask" user "Board Geometry/Soldermask Top")
		(3 "B.Mask" user "Board Geometry/Soldermask Bottom")
		(17 "Dwgs.User" user "User.Drawings")
		(19 "Cmts.User" user "User.Comments")
		(21 "Eco1.User" user "User.Eco1")
		(23 "Eco2.User" user "User.Eco2")
		(25 "Edge.Cuts" user "Board Geometry/Outline")
		(27 "Margin" user)
		(31 "F.CrtYd" user "Package Geometry/Place Bound Top")
		(29 "B.CrtYd" user "Package Geometry/Place Bound Bottom")
		(35 "F.Fab" user "Ref Des/Assembly Top")
		(33 "B.Fab" user "Ref Des/Assembly Bottom")
	)
	(footprint ""
		(layer "B.Cu")
		(at 114.847116 -46.32325 -90)
		(property "Reference" "C107"
			(at 2.00025 43.123866 270)
			(unlocked yes)
			(layer "B.SilkS")
			(effects
				(font
					(size 0.635 0.4064)
					(thickness 0.1524)
				)
				(justify mirror)
			)
		)
		(property "Value" "VAL*"
			(at 0 3.718306 270)
			(unlocked yes)
			(layer "B.Fab")
			(hide yes)
			(effects
				(font
					(size 0.7874 0.5842)
					(thickness 0.127)
				)
				(justify mirror)
			)
		)
		(property "Device Type" "CAPACITOR-G105-0B104-CK,0.1UF,A"
			(at 0 1.432306 270)
			(unlocked yes)
			(layer "B.Fab")
			(hide yes)
			(effects
				(font
					(size 0.7874 0.5842)
					(thickness 0.127)
				)
				(justify mirror)
			)
		)
		(property "User Part Number" "PARTNUM*"
			(at 0 2.575306 270)
			(unlocked yes)
			(layer "Cmts.User")
			(hide yes)
			(effects
				(font
					(size 0.7874 0.5842)
					(thickness 0.127)
				)
				(justify mirror)
			)
		)
		(property "Tolerance" "TOL*"
			(at 0 4.861306 270)
			(unlocked yes)
			(layer "Cmts.User")
			(hide yes)
			(effects
				(font
					(size 0.7874 0.5842)
					(thickness 0.127)
				)
				(justify mirror)
			)
		)
		(duplicate_pad_numbers_are_jumpers no)
		(fp_line
			(start -0.970026 0.4699)
			(end 0.970026 0.4699)
			(stroke
				(width 0.1)
				(type default)
			)
			(layer "B.SilkS")
		)
		(fp_line
			(start 0.970026 0.4699)
			(end 0.970026 -0.4699)
			(stroke
				(width 0.1)
				(type default)
			)
			(layer "B.SilkS")
		)
		(fp_line
			(start -0.970026 -0.4699)
			(end -0.970026 0.4699)
			(stroke
				(width 0.1)
				(type default)
			)
			(layer "B.SilkS")
		)
		(fp_line
			(start 0.970026 -0.4699)
			(end -0.970026 -0.4699)
			(stroke
				(width 0.1)
				(type default)
			)
			(layer "B.SilkS")
		)
		(fp_poly
			(pts
				(xy 0.970026 0.4699) (xy -0.970026 0.4699) (xy -0.970026 -0.4699) (xy 0.970026 -0.4699)
			)
			(stroke
				(width 0)
				(type default)
			)
			(fill no)
			(layer "B.CrtYd")
		)
		(fp_line
			(start -0.508 0.3048)
			(end 0.508 0.3048)
			(stroke
				(width 0.1)
				(type default)
			)
			(layer "B.Fab")
		)
		(fp_line
			(start 0.508 0.3048)
			(end 0.508 -0.3048)
			(stroke
				(width 0.1)
				(type default)
			)
			(layer "B.Fab")
		)
		(fp_line
			(start -0.508 -0.3048)
			(end -0.508 0.3048)
			(stroke
				(width 0.1)
				(type default)
			)
			(layer "B.Fab")
		)
		(fp_line
			(start 0.508 -0.3048)
			(end -0.508 -0.3048)
			(stroke
				(width 0.1)
				(type default)
			)
			(layer "B.Fab")
		)
		(pad "1" smd circle
			(at 0.500126 0 90)
			(size 0.635 0.635)
			(layers "B.Cu" "B.Mask" "B.Paste")
			(net "XP3R3V_FPGA")
		)
		(pad "2" smd circle
			(at -0.500126 0 90)
			(size 0.635 0.635)
			(layers "B.Cu" "B.Mask" "B.Paste")
			(net "SG")
		)
	)
	(footprint ""
		(layer "B.Cu")
		(at 89.027 -45.974 90)
		(property "Reference" "C67"
			(at -0.381 -1.56337 270)
			(unlocked yes)
			(layer "B.SilkS")
			(effects
				(font
					(size 0.7874 0.5842)
					(thickness 0.1524)
				)
				(justify mirror)
			)
		)
		(property "Value" "VAL*"
			(at -0.0762 2.067306 90)
			(unlocked yes)
			(layer "B.Fab")
			(hide yes)
			(effects
				(font
					(size 0.7874 0.5842)
					(thickness 0.1524)
				)
				(justify mirror)
			)
		)
		(property "Device Type" "CAPACITOR-G105-0B104-CK,0.1UF,A"
			(at -0.0508 1.127506 90)
			(unlocked yes)
			(layer "B.Fab")
			(hide yes)
			(effects
				(font
					(size 0.7874 0.5842)
					(thickness 0.1524)
				)
				(justify mirror)
			)
		)
		(property "User Part Number" "PARTNUM*"
			(at -0.1016 4.023106 90)
			(unlocked yes)
			(layer "Cmts.User")
			(hide yes)
			(effects
				(font
					(size 0.7874 0.5842)
					(thickness 0.1524)
				)
				(justify mirror)
			)
		)
		(property "Tolerance" "TOL*"
			(at -0.0762 3.032506 90)
			(unlocked yes)
			(layer "Cmts.User")
			(hide yes)
			(effects
				(font
					(size 0.7874 0.5842)
					(thickness 0.1524)
				)
				(justify mirror)
			)
		)
		(duplicate_pad_numbers_are_jumpers no)
		(fp_line
			(start 1.143 -0.5588)
			(end 1.143 0.5588)
			(stroke
				(width 0.1)
				(type default)
			)
			(layer "B.SilkS")
		)
		(fp_line
			(start -1.143 -0.5588)
			(end 1.143 -0.5588)
			(stroke
				(width 0.1)
				(type default)
			)
			(layer "B.SilkS")
		)
		(fp_line
			(start 1.143 0.5588)
			(end -1.143 0.5588)
			(stroke
				(width 0.1)
				(type default)
			)
			(layer "B.SilkS")
		)
		(fp_line
			(start -1.143 0.5588)
			(end -1.143 -0.5588)
			(stroke
				(width 0.1)
				(type default)
			)
			(layer "B.SilkS")
		)
		(fp_rect
			(start -1.143 0.5588)
			(end 1.143 -0.5588)
			(stroke
				(width 0)
				(type default)
			)
			(fill no)
			(layer "B.CrtYd")
		)
		(fp_line
			(start 0.508 -0.3048)
			(end 0.508 0.3048)
			(stroke
				(width 0.1)
				(type default)
			)
			(layer "B.Fab")
		)
		(fp_line
			(start -0.508 -0.3048)
			(end 0.508 -0.3048)
			(stroke
				(width 0.1)
				(type default)
			)
			(layer "B.Fab")
		)
		(fp_line
			(start 0.508 0.3048)
			(end -0.508 0.3048)
			(stroke
				(width 0.1)
				(type default)
			)
			(layer "B.Fab")
		)
		(fp_line
			(start -0.508 0.3048)
			(end -0.508 -0.3048)
			(stroke
				(width 0.1)
				(type default)
			)
			(layer "B.Fab")
		)
		(pad "1" smd rect
			(at 0.5334 0 270)
			(size 0.7112 0.6096)
			(layers "B.Cu" "B.Mask" "B.Paste")
			(net "XP3R3V_FPGA")
		)
		(pad "2" smd rect
			(at -0.5334 0 270)
			(size 0.7112 0.6096)
			(layers "B.Cu" "B.Mask" "B.Paste")
			(net "SG")
		)
		(zone
			(layer "B.Cu")
			(hatch none 0.5)
			(connect_pads
				(clearance 0)
			)
			(min_thickness 0.25)
			(keepout
				(tracks allowed)
				(vias not_allowed)
				(pads allowed)
				(copperpour not_allowed)
				(footprints allowed)
			)
			(placement
				(enabled no)
				(sheetname "")
			)
			(fill
				(thermal_gap 0.5)
				(thermal_bridge_width 0.5)
				(island_removal_mode 0)
			)
			(polygon
				(pts
					(xy 89.3318 -45.8978) (xy 89.3318 -46.0502) (xy 88.7222 -46.0502) (xy 88.7222 -45.8978)
				)
			)
		)
	)
	(footprint ""
		(layer "B.Cu")
		(at 61.976 -59.817)
		(property "Reference" "C68"
			(at -2.54 0.03937 0)
			(unlocked yes)
			(layer "B.SilkS")
			(effects
				(font
					(size 0.7874 0.5842)
					(thickness 0.1524)
				)
				(justify mirror)
			)
		)
		(property "Value" "VAL*"
			(at -0.0762 2.067306 0)
			(unlocked yes)
			(layer "B.Fab")
			(hide yes)
			(effects
				(font
					(size 0.7874 0.5842)
					(thickness 0.1524)
				)
				(justify mirror)
			)
		)
		(property "Device Type" "CAPACITOR-G105-0B104-EK,0.1UF,A"
			(at -0.0508 1.127506 0)
			(unlocked yes)
			(layer "B.Fab")
			(hide yes)
			(effects
				(font
					(size 0.7874 0.5842)
					(thickness 0.1524)
				)
				(justify mirror)
			)
		)
		(property "User Part Number" "PARTNUM*"
			(at -0.1016 4.023106 0)
			(unlocked yes)
			(layer "Cmts.User")
			(hide yes)
			(effects
				(font
					(size 0.7874 0.5842)
					(thickness 0.1524)
				)
				(justify mirror)
			)
		)
		(property "Tolerance" "TOL*"
			(at -0.0762 3.032506 0)
			(unlocked yes)
			(layer "Cmts.User")
			(hide yes)
			(effects
				(font
					(size 0.7874 0.5842)
					(thickness 0.1524)
				)
				(justify mirror)
			)
		)
		(duplicate_pad_numbers_are_jumpers no)
		(fp_line
			(start -1.143 -0.5588)
			(end 1.143 -0.5588)
			(stroke
				(width 0.1)
				(type default)
			)
			(layer "B.SilkS")
		)
		(fp_line
			(start -1.143 0.5588)
			(end -1.143 -0.5588)
			(stroke
				(width 0.1)
				(type default)
			)
			(layer "B.SilkS")
		)
		(fp_line
			(start 1.143 -0.5588)
			(end 1.143 0.5588)
			(stroke
				(width 0.1)
				(type default)
			)
			(layer "B.SilkS")
		)
		(fp_line
			(start 1.143 0.5588)
			(end -1.143 0.5588)
			(stroke
				(width 0.1)
				(type default)
			)
			(layer "B.SilkS")
		)
		(fp_rect
			(start -1.143 -0.5588)
			(end 1.143 0.5588)
			(stroke
				(width 0)
				(type default)
			)
			(fill no)
			(layer "B.CrtYd")
		)
		(fp_line
			(start -0.508 -0.3048)
			(end 0.508 -0.3048)
			(stroke
				(width 0.1)
				(type default)
			)
			(layer "B.Fab")
		)
		(fp_line
			(start -0.508 0.3048)
			(end -0.508 -0.3048)
			(stroke
				(width 0.1)
				(type default)
			)
			(layer "B.Fab")
		)
		(fp_line
			(start 0.508 -0.3048)
			(end 0.508 0.3048)
			(stroke
				(width 0.1)
				(type default)
			)
			(layer "B.Fab")
		)
		(fp_line
			(start 0.508 0.3048)
			(end -0.508 0.3048)
			(stroke
				(width 0.1)
				(type default)
			)
			(layer "B.Fab")
		)
		(pad "1" smd rect
			(at 0.5334 0 180)
			(size 0.7112 0.6096)
			(layers "B.Cu" "B.Mask" "B.Paste")
			(net "XP3R3V_FPGA")
		)
		(pad "2" smd rect
			(at -0.5334 0 180)
			(size 0.7112 0.6096)
			(layers "B.Cu" "B.Mask" "B.Paste")
			(net "SG")
		)
		(zone
			(layer "B.Cu")
			(hatch none 0.5)
			(connect_pads
				(clearance 0)
			)
			(min_thickness 0.25)
			(keepout
				(tracks allowed)
				(vias not_allowed)
				(pads allowed)
				(copperpour not_allowed)
				(footprints allowed)
			)
			(placement
				(enabled no)
				(sheetname "")
			)
			(fill
				(thermal_gap 0.5)
				(thermal_bridge_width 0.5)
				(island_removal_mode 0)
			)
			(polygon
				(pts
					(xy 61.8998 -60.1218) (xy 61.8998 -59.5122) (xy 62.0522 -59.5122) (xy 62.0522 -60.1218)
				)
			)
		)
		(zone
			(layer "B.Cu")
			(hatch none 0.5)
			(connect_pads
				(clearance 0)
			)
			(min_thickness 0.25)
			(keepout
				(tracks not_allowed)
				(vias allowed)
				(pads allowed)
				(copperpour not_allowed)
				(footprints allowed)
			)
			(placement
				(enabled no)
				(sheetname "")
			)
			(fill
				(thermal_gap 0.5)
				(thermal_bridge_width 0.5)
				(island_removal_mode 0)
			)
			(polygon
				(pts
					(xy 61.8998 -60.1218) (xy 61.8998 -59.5122) (xy 62.0522 -59.5122) (xy 62.0522 -60.1218)
				)
			)
		)
	)
	(footprint ""
		(layer "B.Cu")
		(at 77.3938 -83.947)
		(property "Reference" "R154"
			(at -1.1938 -2.37363 0)
			(unlocked yes)
			(layer "B.SilkS")
			(effects
				(font
					(size 0.7874 0.5842)
					(thickness 0.1524)
				)
				(justify mirror)
			)
		)
		(property "Value" "VAL*"
			(at -0.02032 2.13233 0)
			(unlocked yes)
			(layer "B.Fab")
			(hide yes)
			(effects
				(font
					(size 0.7874 0.5842)
					(thickness 0.1524)
				)
				(justify mirror)
			)
		)
		(property "Tolerance" "TOL*"
			(at -0.044704 3.05435 0)
			(unlocked yes)
			(layer "Cmts.User")
			(hide yes)
			(effects
				(font
					(size 0.7874 0.5842)
					(thickness 0.1524)
				)
				(justify mirror)
			)
		)
		(property "User Part Number" "PARTNUM*"
			(at -0.02032 4.024884 0)
			(unlocked yes)
			(layer "Cmts.User")
			(hide yes)
			(effects
				(font
					(size 0.7874 0.5842)
					(thickness 0.1524)
				)
				(justify mirror)
			)
		)
		(property "Device Type" "RESISTOR-G155-14701-01,4.7KOHMA"
			(at -0.008382 1.210564 0)
			(unlocked yes)
			(layer "B.Fab")
			(hide yes)
			(effects
				(font
					(size 0.7874 0.5842)
					(thickness 0.1524)
				)
				(justify mirror)
			)
		)
		(duplicate_pad_numbers_are_jumpers no)
		(fp_line
			(start -1.143 -0.5588)
			(end 1.143 -0.5588)
			(stroke
				(width 0.1)
				(type default)
			)
			(layer "B.SilkS")
		)
		(fp_line
			(start -1.143 0.5588)
			(end -1.143 -0.5588)
			(stroke
				(width 0.1)
				(type default)
			)
			(layer "B.SilkS")
		)
		(fp_line
			(start 1.143 -0.5588)
			(end 1.143 0.5588)
			(stroke
				(width 0.1)
				(type default)
			)
			(layer "B.SilkS")
		)
		(fp_line
			(start 1.143 0.5588)
			(end -1.143 0.5588)
			(stroke
				(width 0.1)
				(type default)
			)
			(layer "B.SilkS")
		)
		(fp_rect
			(start 1.143 -0.5588)
			(end -1.143 0.5588)
			(stroke
				(width 0)
				(type default)
			)
			(fill no)
			(layer "B.CrtYd")
		)
		(fp_line
			(start -0.508 -0.3048)
			(end 0.508 -0.3048)
			(stroke
				(width 0.1)
				(type default)
			)
			(layer "B.Fab")
		)
		(fp_line
			(start -0.508 0.3048)
			(end -0.508 -0.3048)
			(stroke
				(width 0.1)
				(type default)
			)
			(layer "B.Fab")
		)
		(fp_line
			(start 0.508 -0.3048)
			(end 0.508 0.3048)
			(stroke
				(width 0.1)
				(type default)
			)
			(layer "B.Fab")
		)
		(fp_line
			(start 0.508 0.3048)
			(end -0.508 0.3048)
			(stroke
				(width 0.1)
				(type default)
			)
			(layer "B.Fab")
		)
		(pad "1" smd rect
			(at 0.5334 0 180)
			(size 0.7112 0.6096)
			(layers "B.Cu" "B.Mask" "B.Paste")
			(net "SG")
		)
		(pad "2" smd rect
			(at -0.5334 0 180)
			(size 0.7112 0.6096)
			(layers "B.Cu" "B.Mask" "B.Paste")
			(net "UNNAMED_5_PCA9546APWTSSOP16_I_2")
		)
		(zone
			(layer "B.Cu")
			(hatch none 0.5)
			(connect_pads
				(clearance 0)
			)
			(min_thickness 0.25)
			(keepout
				(tracks allowed)
				(vias not_allowed)
				(pads allowed)
				(copperpour not_allowed)
				(footprints allowed)
			)
			(placement
				(enabled no)
				(sheetname "")
			)
			(fill
				(thermal_gap 0.5)
				(thermal_bridge_width 0.5)
				(island_removal_mode 0)
			)
			(polygon
				(pts
					(xy 77.47 -84.2518) (xy 77.3176 -84.2518) (xy 77.3176 -83.6422) (xy 77.47 -83.6422)
				)
			)
		)
	)
	(footprint ""
		(layer "B.Cu")
		(at 139.6492 -85.4456)
		(property "Reference" "C297"
			(at 0.4318 -5.82803 0)
			(unlocked yes)
			(layer "B.SilkS")
			(effects
				(font
					(size 0.7874 0.5842)
					(thickness 0.1524)
				)
				(justify mirror)
			)
		)
		(property "Value" "VAL*"
			(at -0.0762 3.134106 0)
			(unlocked yes)
			(layer "B.Fab")
			(hide yes)
			(effects
				(font
					(size 0.7874 0.5842)
					(thickness 0.1524)
				)
				(justify mirror)
			)
		)
		(property "Device Type" "CAPACITOR-G107-0F106-EM,10UF,2A"
			(at -0.0508 2.194306 0)
			(unlocked yes)
			(layer "B.Fab")
			(hide yes)
			(effects
				(font
					(size 0.7874 0.5842)
					(thickness 0.1524)
				)
				(justify mirror)
			)
		)
		(property "User Part Number" "PARTNUM*"
			(at -0.1016 5.013706 0)
			(unlocked yes)
			(layer "Cmts.User")
			(hide yes)
			(effects
				(font
					(size 0.7874 0.5842)
					(thickness 0.1524)
				)
				(justify mirror)
			)
		)
		(property "Tolerance" "TOL*"
			(at -0.0762 4.048506 0)
			(unlocked yes)
			(layer "Cmts.User")
			(hide yes)
			(effects
				(font
					(size 0.7874 0.5842)
					(thickness 0.1524)
				)
				(justify mirror)
			)
		)
		(duplicate_pad_numbers_are_jumpers no)
		(fp_line
			(start -1.5748 -0.9398)
			(end 1.5748 -0.9398)
			(stroke
				(width 0.1)
				(type default)
			)
			(layer "B.SilkS")
		)
		(fp_line
			(start -1.5748 0.9398)
			(end -1.5748 -0.9398)
			(stroke
				(width 0.1)
				(type default)
			)
			(layer "B.SilkS")
		)
		(fp_line
			(start 1.5748 -0.9398)
			(end 1.5748 0.9398)
			(stroke
				(width 0.1)
				(type default)
			)
			(layer "B.SilkS")
		)
		(fp_line
			(start 1.5748 0.9398)
			(end -1.5748 0.9398)
			(stroke
				(width 0.1)
				(type default)
			)
			(layer "B.SilkS")
		)
		(fp_rect
			(start 1.5748 -0.9398)
			(end -1.5748 0.9398)
			(stroke
				(width 0)
				(type default)
			)
			(fill no)
			(layer "B.CrtYd")
		)
		(fp_line
			(start -1.016 -0.635)
			(end 1.016 -0.635)
			(stroke
				(width 0.1)
				(type default)
			)
			(layer "B.Fab")
		)
		(fp_line
			(start -1.016 0.635)
			(end -1.016 -0.635)
			(stroke
				(width 0.1)
				(type default)
			)
			(layer "B.Fab")
		)
		(fp_line
			(start 1.016 -0.635)
			(end 1.016 0.635)
			(stroke
				(width 0.1)
				(type default)
			)
			(layer "B.Fab")
		)
		(fp_line
			(start 1.016 0.635)
			(end -1.016 0.635)
			(stroke
				(width 0.1)
				(type default)
			)
			(layer "B.Fab")
		)
		(pad "1" smd rect
			(at 0.8382 0 180)
			(size 0.9652 1.3716)
			(layers "B.Cu" "B.Mask" "B.Paste")
			(net "XP12R0V_IN")
		)
		(pad "2" smd rect
			(at -0.8382 0 180)
			(size 0.9652 1.3716)
			(layers "B.Cu" "B.Mask" "B.Paste")
			(net "SG")
		)
		(zone
			(layer "B.Cu")
			(hatch none 0.5)
			(connect_pads
				(clearance 0)
			)
			(min_thickness 0.25)
			(keepout
				(tracks not_allowed)
				(vias allowed)
				(pads allowed)
				(copperpour not_allowed)
				(footprints allowed)
			)
			(placement
				(enabled no)
				(sheetname "")
			)
			(fill
				(thermal_gap 0.5)
				(thermal_bridge_width 0.5)
				(island_removal_mode 0)
			)
			(polygon
				(pts
					(xy 139.8778 -86.0806) (xy 139.4206 -86.0806) (xy 139.4206 -84.8106) (xy 139.8778 -84.8106)
				)
			)
		)
		(zone
			(layer "B.Cu")
			(hatch none 0.5)
			(connect_pads
				(clearance 0)
			)
			(min_thickness 0.25)
			(keepout
				(tracks allowed)
				(vias not_allowed)
				(pads allowed)
				(copperpour not_allowed)
				(footprints allowed)
			)
			(placement
				(enabled no)
				(sheetname "")
			)
			(fill
				(thermal_gap 0.5)
				(thermal_bridge_width 0.5)
				(island_removal_mode 0)
			)
			(polygon
				(pts
					(xy 139.8778 -86.0806) (xy 139.4206 -86.0806) (xy 139.4206 -84.8106) (xy 139.8778 -84.8106)
				)
			)
		)
	)
)
